(kicad_pcb
	(version 20241229)
	(generator "pcbnew")
	(generator_version "9.0")
	(general
		(thickness 1.63)
		(legacy_teardrops no)
	)
	(paper "A4")
	(title_block
		(title "CM4 Baseboard")
		(date "2026-01-05")
		(rev "1.1.1")
		(company "Antmicro Ltd")
		(comment 1 "www.antmicro.com")
		(comment 9 "footprints 384-386 of 506")
	)
	(layers
		(0 "F.Cu" signal)
		(4 "In1.Cu" power)
		(6 "In2.Cu" power)
		(8 "In3.Cu" signal)
		(10 "In4.Cu" signal)
		(2 "B.Cu" signal)
		(9 "F.Adhes" user "F.Adhesive")
		(11 "B.Adhes" user "B.Adhesive")
		(13 "F.Paste" user)
		(15 "B.Paste" user)
		(5 "F.SilkS" user "F.Silkscreen")
		(7 "B.SilkS" user "B.Silkscreen")
		(1 "F.Mask" user)
		(3 "B.Mask" user)
		(17 "Dwgs.User" user "User.Drawings")
		(19 "Cmts.User" user "User.Comments")
		(21 "Eco1.User" user "User.Eco1")
		(23 "Eco2.User" user "User.Eco2")
		(25 "Edge.Cuts" user)
		(27 "Margin" user)
		(31 "F.CrtYd" user "F.Courtyard")
		(29 "B.CrtYd" user "B.Courtyard")
		(35 "F.Fab" user)
		(33 "B.Fab" user)
	)
	(footprint "antmicro-footprints:Spacer_Drill3.7mm_H2.5mm_9774025151R"
		(locked yes)
		(layer "B.Cu")
		(at 44.992962 124.767)
		(descr "Spacer M=3 h=2.5mm fi=5.1mm")
		(property "Reference" "H501"
			(at 1.405 -3.3305 180)
			(layer "B.SilkS")
			(effects
				(font
					(size 0.7 0.7)
					(thickness 0.15)
				)
				(justify left bottom mirror)
			)
		)
		(property "Value" "Spacer_Drill3.7mm_H2.5mm_9774025151R"
			(at 0 -4 180)
			(layer "B.Fab")
			(effects
				(font
					(size 0.7 0.7)
					(thickness 0.15)
				)
				(justify left bottom mirror)
			)
		)
		(property "Datasheet" "https://www.we-online.com/components/products/datasheet/9774025151R.pdf"
			(at 0 0 0)
			(layer "B.Fab")
			(hide yes)
			(effects
				(font
					(size 1.27 1.27)
					(thickness 0.15)
				)
			)
		)
		(property "Manufacturer" "Würth Elektronik"
			(at 0 0 0)
			(unlocked yes)
			(layer "B.Fab")
			(hide yes)
			(effects
				(font
					(size 1 1)
					(thickness 0.15)
				)
				(justify mirror)
			)
		)
		(property "MPN" "9774025151R"
			(at 0 0 0)
			(unlocked yes)
			(layer "B.Fab")
			(hide yes)
			(effects
				(font
					(size 1 1)
					(thickness 0.15)
				)
				(justify mirror)
			)
		)
		(property "Author" "Antmicro"
			(at 0 0 0)
			(unlocked yes)
			(layer "B.Fab")
			(hide yes)
			(effects
				(font
					(size 1 1)
					(thickness 0.15)
				)
				(justify mirror)
			)
		)
		(property "License" "Apache-2.0"
			(at 0 0 0)
			(unlocked yes)
			(layer "B.Fab")
			(hide yes)
			(effects
				(font
					(size 1 1)
					(thickness 0.15)
				)
				(justify mirror)
			)
		)
		(sheetname "/NVMe & microSD/")
		(sheetfile "nvme-micro-sd.kicad_sch")
		(solder_paste_margin_ratio -1)
		(attr smd)
		(fp_circle
			(center 0 0)
			(end 3.05 0)
			(stroke
				(width 0.05)
				(type solid)
			)
			(fill no)
			(layer "B.CrtYd")
		)
		(fp_circle
			(center 0 0)
			(end 2.6 0)
			(stroke
				(width 0.15)
				(type solid)
			)
			(fill no)
			(layer "B.Fab")
		)
		(fp_text user "Author: Antmicro"
			(at -9.6 -7.7 180)
			(layer "B.Fab")
			(effects
				(font
					(size 0.7 0.7)
					(thickness 0.15)
				)
				(justify left bottom mirror)
			)
		)
		(fp_text user "License: Apache-2.0"
			(at -9.6 -8.9 180)
			(layer "B.Fab")
			(effects
				(font
					(size 0.7 0.7)
					(thickness 0.15)
				)
				(justify left bottom mirror)
			)
		)
		(fp_text user "${REFERENCE}"
			(at -9.6 -6.5 180)
			(layer "B.Fab")
			(effects
				(font
					(size 0.7 0.7)
					(thickness 0.15)
				)
				(justify left bottom mirror)
			)
		)
		(pad "" smd custom
			(at -1.7 -1.7 270)
			(size 0.62 0.62)
			(layers "B.Paste")
			(thermal_bridge_angle 90)
			(options
				(clearance outline)
				(anchor circle)
			)
			(primitives
				(gr_arc
					(start 1.266786 0.24747)
					(mid 0.285453 -0.29439)
					(end -0.250195 -1.279127)
					(width 0.2)
				)
				(gr_arc
					(start 1.259603 0.339191)
					(mid 0.218448 -0.232561)
					(end -0.34334 -1.279127)
					(width 0.2)
				)
				(gr_arc
					(start 1.255279 0.431435)
					(mid 0.152481 -0.169693)
					(end -0.436309 -1.279127)
					(width 0.2)
				)
				(gr_arc
					(start 1.253811 0.524161)
					(mid 0.087542 -0.105784)
					(end -0.529126 -1.279127)
					(width 0.2)
				)
				(gr_arc
					(start 1.275473 0.621136)
					(mid 0.0309 -0.033527)
					(end -0.621807 -1.279127)
					(width 0.2)
				)
				(gr_arc
					(start 1.263664 0.711602)
					(mid -0.037759 0.026651)
					(end -0.71437 -1.279127)
					(width 0.2)
				)
				(gr_arc
					(start 1.253435 0.802342)
					(mid -0.105837 0.087395)
					(end -0.806826 -1.279127)
					(width 0.2)
				)
				(gr_arc
					(start 1.267475 0.897258)
					(mid -0.165236 0.156885)
					(end -0.899187 -1.279127)
					(width 0.2)
				)
				(gr_arc
					(start 1.270645 0.990112)
					(mid -0.228522 0.222449)
					(end -0.991463 -1.279127)
					(width 0.2)
				)
				(gr_arc
					(start 1.266278 1.081674)
					(mid -0.294507 0.285313)
					(end -1.083663 -1.279127)
					(width 0.2)
				)
				(gr_line
					(start 1.279127 0.250195)
					(end 1.279127 1.083663)
					(width 0.2)
				)
				(gr_line
					(start -0.250195 -1.279127)
					(end -1.083663 -1.279127)
					(width 0.2)
				)
			)
		)
		(pad "" smd custom
			(at -1.7 1.7)
			(size 0.62 0.62)
			(layers "B.Paste")
			(thermal_bridge_angle 90)
			(options
				(clearance outline)
				(anchor circle)
			)
			(primitives
				(gr_arc
					(start 1.266786 0.24747)
					(mid 0.285453 -0.29439)
					(end -0.250195 -1.279127)
					(width 0.2)
				)
				(gr_arc
					(start 1.259603 0.339191)
					(mid 0.218448 -0.232561)
					(end -0.34334 -1.279127)
					(width 0.2)
				)
				(gr_arc
					(start 1.255279 0.431435)
					(mid 0.152481 -0.169693)
					(end -0.436309 -1.279127)
					(width 0.2)
				)
				(gr_arc
					(start 1.253811 0.524161)
					(mid 0.087542 -0.105784)
					(end -0.529126 -1.279127)
					(width 0.2)
				)
				(gr_arc
					(start 1.275473 0.621136)
					(mid 0.0309 -0.033527)
					(end -0.621807 -1.279127)
					(width 0.2)
				)
				(gr_arc
					(start 1.263664 0.711602)
					(mid -0.037759 0.026651)
					(end -0.71437 -1.279127)
					(width 0.2)
				)
				(gr_arc
					(start 1.253435 0.802342)
					(mid -0.105837 0.087395)
					(end -0.806826 -1.279127)
					(width 0.2)
				)
				(gr_arc
					(start 1.267475 0.897258)
					(mid -0.165236 0.156885)
					(end -0.899187 -1.279127)
					(width 0.2)
				)
				(gr_arc
					(start 1.270645 0.990112)
					(mid -0.228522 0.222449)
					(end -0.991463 -1.279127)
					(width 0.2)
				)
				(gr_arc
					(start 1.266278 1.081674)
					(mid -0.294507 0.285313)
					(end -1.083663 -1.279127)
					(width 0.2)
				)
				(gr_line
					(start 1.279127 0.250195)
					(end 1.279127 1.083663)
					(width 0.2)
				)
				(gr_line
					(start -0.250195 -1.279127)
					(end -1.083663 -1.279127)
					(width 0.2)
				)
			)
		)
		(pad "" smd custom
			(at 1.7 -1.7 180)
			(size 0.62 0.62)
			(layers "B.Paste")
			(thermal_bridge_angle 90)
			(options
				(clearance outline)
				(anchor circle)
			)
			(primitives
				(gr_arc
					(start 1.266786 0.24747)
					(mid 0.285453 -0.29439)
					(end -0.250195 -1.279127)
					(width 0.2)
				)
				(gr_arc
					(start 1.259603 0.339191)
					(mid 0.218448 -0.232561)
					(end -0.34334 -1.279127)
					(width 0.2)
				)
				(gr_arc
					(start 1.255279 0.431435)
					(mid 0.152481 -0.169693)
					(end -0.436309 -1.279127)
					(width 0.2)
				)
				(gr_arc
					(start 1.253811 0.524161)
					(mid 0.087542 -0.105784)
					(end -0.529126 -1.279127)
					(width 0.2)
				)
				(gr_arc
					(start 1.275473 0.621136)
					(mid 0.0309 -0.033527)
					(end -0.621807 -1.279127)
					(width 0.2)
				)
				(gr_arc
					(start 1.263664 0.711602)
					(mid -0.037759 0.026651)
					(end -0.71437 -1.279127)
					(width 0.2)
				)
				(gr_arc
					(start 1.253435 0.802342)
					(mid -0.105837 0.087395)
					(end -0.806826 -1.279127)
					(width 0.2)
				)
				(gr_arc
					(start 1.267475 0.897258)
					(mid -0.165236 0.156885)
					(end -0.899187 -1.279127)
					(width 0.2)
				)
				(gr_arc
					(start 1.270645 0.990112)
					(mid -0.228522 0.222449)
					(end -0.991463 -1.279127)
					(width 0.2)
				)
				(gr_arc
					(start 1.266278 1.081674)
					(mid -0.294507 0.285313)
					(end -1.083663 -1.279127)
					(width 0.2)
				)
				(gr_line
					(start 1.279127 0.250195)
					(end 1.279127 1.083663)
					(width 0.2)
				)
				(gr_line
					(start -0.250195 -1.279127)
					(end -1.083663 -1.279127)
					(width 0.2)
				)
			)
		)
		(pad "" smd custom
			(at 1.7 1.7 90)
			(size 0.62 0.62)
			(layers "B.Paste")
			(thermal_bridge_angle 90)
			(options
				(clearance outline)
				(anchor circle)
			)
			(primitives
				(gr_arc
					(start 1.266786 0.24747)
					(mid 0.285453 -0.29439)
					(end -0.250195 -1.279127)
					(width 0.2)
				)
				(gr_arc
					(start 1.259603 0.339191)
					(mid 0.218448 -0.232561)
					(end -0.34334 -1.279127)
					(width 0.2)
				)
				(gr_arc
					(start 1.255279 0.431435)
					(mid 0.152481 -0.169693)
					(end -0.436309 -1.279127)
					(width 0.2)
				)
				(gr_arc
					(start 1.253811 0.524161)
					(mid 0.087542 -0.105784)
					(end -0.529126 -1.279127)
					(width 0.2)
				)
				(gr_arc
					(start 1.275473 0.621136)
					(mid 0.0309 -0.033527)
					(end -0.621807 -1.279127)
					(width 0.2)
				)
				(gr_arc
					(start 1.263664 0.711602)
					(mid -0.037759 0.026651)
					(end -0.71437 -1.279127)
					(width 0.2)
				)
				(gr_arc
					(start 1.253435 0.802342)
					(mid -0.105837 0.087395)
					(end -0.806826 -1.279127)
					(width 0.2)
				)
				(gr_arc
					(start 1.267475 0.897258)
					(mid -0.165236 0.156885)
					(end -0.899187 -1.279127)
					(width 0.2)
				)
				(gr_arc
					(start 1.270645 0.990112)
					(mid -0.228522 0.222449)
					(end -0.991463 -1.279127)
					(width 0.2)
				)
				(gr_arc
					(start 1.266278 1.081674)
					(mid -0.294507 0.285313)
					(end -1.083663 -1.279127)
					(width 0.2)
				)
				(gr_line
					(start 1.279127 0.250195)
					(end 1.279127 1.083663)
					(width 0.2)
				)
				(gr_line
					(start -0.250195 -1.279127)
					(end -1.083663 -1.279127)
					(width 0.2)
				)
			)
		)
		(pad "1" thru_hole circle
			(at 0 0)
			(size 6 6)
			(drill 3.7)
			(layers "*.Cu" "*.Mask")
			(remove_unused_layers no)
			(net 3 "GND")
			(pintype "passive")
		)
	)
	(footprint "antmicro-footprints:C_0402_1005Metric"
		(layer "B.Cu")
		(at 88.742962 123.1415 180)
		(descr "Capacitor SMD 0402")
		(tags "capacitor SMD 0402")
		(property "Reference" "C906"
			(at 2.835 0.375 0)
			(layer "B.SilkS")
			(effects
				(font
					(size 0.7 0.7)
					(thickness 0.15)
				)
				(justify left bottom mirror)
			)
		)
		(property "Value" "C_100n_0402"
			(at -1.022927 -2.155213 0)
			(layer "B.Fab")
			(effects
				(font
					(size 0.7 0.7)
					(thickness 0.15)
				)
				(justify left bottom mirror)
			)
		)
		(property "Datasheet" "https://www.murata.com/products/productdetail?partno=GRM155R61H104KE14%23"
			(at 0 0 180)
			(layer "B.Fab")
			(hide yes)
			(effects
				(font
					(size 1.27 1.27)
					(thickness 0.15)
				)
			)
		)
		(property "Manufacturer" "Murata"
			(at 0 0 180)
			(unlocked yes)
			(layer "B.Fab")
			(hide yes)
			(effects
				(font
					(size 1 1)
					(thickness 0.15)
				)
				(justify mirror)
			)
		)
		(property "MPN" "GRM155R61H104KE14D"
			(at 0 0 180)
			(unlocked yes)
			(layer "B.Fab")
			(hide yes)
			(effects
				(font
					(size 1 1)
					(thickness 0.15)
				)
				(justify mirror)
			)
		)
		(property "Val" "100n"
			(at 0 0 180)
			(unlocked yes)
			(layer "B.Fab")
			(hide yes)
			(effects
				(font
					(size 1 1)
					(thickness 0.15)
				)
				(justify mirror)
			)
		)
		(property "License" "Apache-2.0"
			(at 0 0 180)
			(unlocked yes)
			(layer "B.Fab")
			(hide yes)
			(effects
				(font
					(size 1 1)
					(thickness 0.15)
				)
				(justify mirror)
			)
		)
		(property "Author" "Antmicro"
			(at 0 0 180)
			(unlocked yes)
			(layer "B.Fab")
			(hide yes)
			(effects
				(font
					(size 1 1)
					(thickness 0.15)
				)
				(justify mirror)
			)
		)
		(property "Voltage" "50V"
			(at 0 0 180)
			(unlocked yes)
			(layer "B.Fab")
			(hide yes)
			(effects
				(font
					(size 1 1)
					(thickness 0.15)
				)
				(justify mirror)
			)
		)
		(property "Dielectric" "X5R"
			(at 0 0 180)
			(unlocked yes)
			(layer "B.Fab")
			(hide yes)
			(effects
				(font
					(size 1 1)
					(thickness 0.15)
				)
				(justify mirror)
			)
		)
		(sheetname "/USB/")
		(sheetfile "usb.kicad_sch")
		(attr smd)
		(fp_rect
			(start -0.925 0.47)
			(end 0.925 -0.47)
			(stroke
				(width 0.05)
				(type default)
			)
			(fill no)
			(layer "B.CrtYd")
		)
		(fp_line
			(start 0.504 0.25)
			(end 0.504 -0.248)
			(stroke
				(width 0.15)
				(type solid)
			)
			(layer "B.Fab")
		)
		(fp_line
			(start 0.504 -0.248)
			(end -0.494 -0.248)
			(stroke
				(width 0.15)
				(type solid)
			)
			(layer "B.Fab")
		)
		(fp_line
			(start -0.494 0.25)
			(end 0.504 0.25)
			(stroke
				(width 0.15)
				(type solid)
			)
			(layer "B.Fab")
		)
		(fp_line
			(start -0.494 -0.248)
			(end -0.494 0.25)
			(stroke
				(width 0.15)
				(type solid)
			)
			(layer "B.Fab")
		)
		(fp_text user "License: Apache-2.0"
			(at -0.939 -5.799 0)
			(layer "B.Fab")
			(effects
				(font
					(size 0.7 0.7)
					(thickness 0.15)
				)
				(justify left bottom mirror)
			)
		)
		(fp_text user "${REFERENCE}"
			(at -0.939 -4.599 0)
			(layer "B.Fab")
			(effects
				(font
					(size 0.7 0.7)
					(thickness 0.15)
				)
				(justify left bottom mirror)
			)
		)
		(fp_text user "Author: Antmicro"
			(at -0.939 -3.399 0)
			(layer "B.Fab")
			(effects
				(font
					(size 0.7 0.7)
					(thickness 0.15)
				)
				(justify left bottom mirror)
			)
		)
		(pad "1" smd roundrect
			(at -0.48 0 180)
			(size 0.59 0.64)
			(layers "B.Cu" "B.Mask" "B.Paste")
			(roundrect_rratio 0.25)
			(net 111 "/USB/SW_FTDI")
			(pintype "passive")
		)
		(pad "2" smd roundrect
			(at 0.48 0 180)
			(size 0.59 0.64)
			(layers "B.Cu" "B.Mask" "B.Paste")
			(roundrect_rratio 0.25)
			(net 112 "Net-(U903-BST)")
			(pintype "passive")
		)
	)
	(footprint "antmicro-footprints:TP_SMD_0.75mm"
		(layer "B.Cu")
		(at 76.792962 135.0415)
		(property "Reference" "TP902"
			(at -0.875 -0.585 0)
			(layer "B.SilkS")
			(effects
				(font
					(size 0.7 0.7)
					(thickness 0.15)
				)
				(justify right bottom mirror)
			)
		)
		(property "Value" "TP_0.75mm_SMD"
			(at 0 -1.2 0)
			(layer "B.Fab")
			(effects
				(font
					(size 0.7 0.7)
					(thickness 0.15)
				)
				(justify right bottom mirror)
			)
		)
		(property "MPN" ""
			(at 0 0 0)
			(unlocked yes)
			(layer "B.Fab")
			(hide yes)
			(effects
				(font
					(size 1 1)
					(thickness 0.15)
				)
				(justify mirror)
			)
		)
		(property "Manufacturer" ""
			(at 0 0 0)
			(unlocked yes)
			(layer "B.Fab")
			(hide yes)
			(effects
				(font
					(size 1 1)
					(thickness 0.15)
				)
				(justify mirror)
			)
		)
		(property "Author" "Antmicro"
			(at 0 0 0)
			(unlocked yes)
			(layer "B.Fab")
			(hide yes)
			(effects
				(font
					(size 1 1)
					(thickness 0.15)
				)
				(justify mirror)
			)
		)
		(property "License" "Apache-2.0"
			(at 0 0 0)
			(unlocked yes)
			(layer "B.Fab")
			(hide yes)
			(effects
				(font
					(size 1 1)
					(thickness 0.15)
				)
				(justify mirror)
			)
		)
		(sheetname "/USB/")
		(sheetfile "usb.kicad_sch")
		(attr exclude_from_pos_files exclude_from_bom)
		(fp_circle
			(center 0 0)
			(end 0.475 0)
			(stroke
				(width 0.05)
				(type default)
			)
			(fill no)
			(layer "B.CrtYd")
		)
		(fp_text user "${REFERENCE}"
			(at -0.4 -2.7 180)
			(layer "B.Fab")
			(effects
				(font
					(size 0.7 0.7)
					(thickness 0.15)
				)
				(justify left bottom mirror)
			)
		)
		(fp_text user "Author: Antmicro"
			(at -0.4 -3.901 180)
			(layer "B.Fab")
			(effects
				(font
					(size 0.7 0.7)
					(thickness 0.15)
				)
				(justify left bottom mirror)
			)
		)
		(fp_text user "License: Apache-2.0"
			(at -0.4 -5.101 180)
			(layer "B.Fab")
			(effects
				(font
					(size 0.7 0.7)
					(thickness 0.15)
				)
				(justify left bottom mirror)
			)
		)
		(pad "1" smd circle
			(at 0 0)
			(size 0.75 0.75)
			(layers "B.Cu" "B.Mask")
			(net 29 "/USB/USBD_SVBUS")
			(pinfunction "1")
			(pintype "passive")
		)
	)
)
